# SCM (Grand Teton) — schematic netlist excerpt (pin names and nets, part order shuffled) for the footprints in the layout excerpt that follows; sources: Cadence DE-HDL packaged netlist, KiCad conversion of 12092022_DA0F0TMDCD0_F0T_Management_Board_D_brd_V3_OCP.brd

R793  Q_RES  665 1% CHIP  pkg 0402LF  page 15 : A = P1V8_AUX ; B = P1V8_SENSOR
R802  Q_RES  33.2 1% CHIP  pkg 0402LF  page 13 : A = SPI_BMC_BOOT_CS1_R_N ; B = SPI_BMC_BOOT_CS1_R1_N

(kicad_pcb
	(version 20260206)
	(generator "pcbnew")
	(generator_version "10.0")
	(general
		(thickness 1.6)
		(legacy_teardrops no)
	)
	(paper "A4")
	(title_block
		(title "12092022_DA0F0TMDCD0_F0T_Management_Board_D_brd_V3_OCP.brd")
		(comment 1 "Grand Teton / footprints 1211-1212 of 1440")
	)
	(layers
		(0 "F.Cu" signal "TOP")
		(4 "In1.Cu" signal "GND")
		(6 "In2.Cu" signal "IN1")
		(8 "In3.Cu" signal "GND1")
		(10 "In4.Cu" signal "IN2")
		(12 "In5.Cu" signal "VCC")
		(14 "In6.Cu" signal "VCC1")
		(16 "In7.Cu" signal "IN3")
		(18 "In8.Cu" signal "GND2")
		(20 "In9.Cu" signal "IN4")
		(22 "In10.Cu" signal "GND3")
		(2 "B.Cu" signal "BOTTOM")
		(9 "F.Adhes" user "F.Adhesive")
		(11 "B.Adhes" user "B.Adhesive")
		(13 "F.Paste" user "Package Geometry/Pastemask Top")
		(15 "B.Paste" user "Package Geometry/Pastemask Bottom")
		(5 "F.SilkS" user "Ref Des/Silkscreen Top")
		(7 "B.SilkS" user "Ref Des/Silkscreen Bottom")
		(1 "F.Mask" user "Board Geometry/Soldermask Top")
		(3 "B.Mask" user "Board Geometry/Soldermask Bottom")
		(17 "Dwgs.User" user "User.Drawings")
		(19 "Cmts.User" user "User.Comments")
		(21 "Eco1.User" user "User.Eco1")
		(23 "Eco2.User" user "User.Eco2")
		(25 "Edge.Cuts" user "Board Geometry/Outline")
		(27 "Margin" user)
		(31 "F.CrtYd" user "Package Geometry/Place Bound Top")
		(29 "B.CrtYd" user "Package Geometry/Place Bound Bottom")
		(35 "F.Fab" user "Ref Des/Assembly Top")
		(33 "B.Fab" user "Ref Des/Assembly Bottom")
	)
	(footprint ""
		(layer "B.Cu")
		(at 50.858674 -72.842374)
		(property "Reference" "R793"
			(at 0 0 0)
			(layer "B.SilkS")
			(hide yes)
			(effects
				(font
					(size 1.27 1.27)
				)
				(justify mirror)
			)
		)
		(property "Value" ""
			(at 0 0 0)
			(layer "B.Fab")
			(effects
				(font
					(size 1.27 1.27)
				)
				(justify mirror)
			)
		)
		(duplicate_pad_numbers_are_jumpers no)
		(fp_line
			(start -0.7874 -0.4064)
			(end -0.7874 0.4064)
			(stroke
				(width 0.1524)
				(type default)
			)
			(layer "B.SilkS")
		)
		(fp_line
			(start -0.7874 0.4064)
			(end 0.7874 0.4064)
			(stroke
				(width 0.1524)
				(type default)
			)
			(layer "B.SilkS")
		)
		(fp_line
			(start 0.7874 -0.4064)
			(end -0.7874 -0.4064)
			(stroke
				(width 0.1524)
				(type default)
			)
			(layer "B.SilkS")
		)
		(fp_line
			(start 0.7874 0.4064)
			(end 0.7874 -0.4064)
			(stroke
				(width 0.1524)
				(type default)
			)
			(layer "B.SilkS")
		)
		(fp_line
			(start -0.67945 -0.3048)
			(end -0.67945 0.3048)
			(stroke
				(width 0.1)
				(type default)
			)
			(layer "B.Fab")
		)
		(fp_line
			(start -0.67945 0.3048)
			(end -0.120396 0.3048)
			(stroke
				(width 0.1)
				(type default)
			)
			(layer "B.Fab")
		)
		(fp_line
			(start -0.12065 -0.3048)
			(end -0.67945 -0.3048)
			(stroke
				(width 0.1)
				(type default)
			)
			(layer "B.Fab")
		)
		(fp_line
			(start -0.12065 -0.2794)
			(end -0.12065 -0.3048)
			(stroke
				(width 0.1)
				(type default)
			)
			(layer "B.Fab")
		)
		(fp_line
			(start -0.120396 0.2794)
			(end 0.12065 0.2794)
			(stroke
				(width 0.1)
				(type default)
			)
			(layer "B.Fab")
		)
		(fp_line
			(start -0.120396 0.3048)
			(end -0.120396 0.2794)
			(stroke
				(width 0.1)
				(type default)
			)
			(layer "B.Fab")
		)
		(fp_line
			(start 0.12065 -0.305054)
			(end 0.12065 -0.2794)
			(stroke
				(width 0.1)
				(type default)
			)
			(layer "B.Fab")
		)
		(fp_line
			(start 0.12065 -0.2794)
			(end -0.12065 -0.2794)
			(stroke
				(width 0.1)
				(type default)
			)
			(layer "B.Fab")
		)
		(fp_line
			(start 0.12065 0.2794)
			(end 0.12065 0.3048)
			(stroke
				(width 0.1)
				(type default)
			)
			(layer "B.Fab")
		)
		(fp_line
			(start 0.12065 0.3048)
			(end 0.67945 0.3048)
			(stroke
				(width 0.1)
				(type default)
			)
			(layer "B.Fab")
		)
		(fp_line
			(start 0.67945 -0.305054)
			(end 0.12065 -0.305054)
			(stroke
				(width 0.1)
				(type default)
			)
			(layer "B.Fab")
		)
		(fp_line
			(start 0.67945 0.3048)
			(end 0.67945 -0.305054)
			(stroke
				(width 0.1)
				(type default)
			)
			(layer "B.Fab")
		)
		(pad "1" smd circle
			(at 0.40005 0 180)
			(size 0 0)
			(layers "B.Cu" "B.Mask" "B.Paste")
			(net "P1V8_AUX")
		)
		(pad "2" smd circle
			(at -0.40005 0 180)
			(size 0 0)
			(layers "B.Cu" "B.Mask" "B.Paste")
			(net "P1V8_SENSOR")
		)
	)
	(footprint ""
		(layer "B.Cu")
		(at 57.687464 -63.861696 90)
		(property "Reference" "R802"
			(at 0 0 90)
			(layer "B.SilkS")
			(hide yes)
			(effects
				(font
					(size 1.27 1.27)
				)
				(justify mirror)
			)
		)
		(property "Value" ""
			(at 0 0 90)
			(layer "B.Fab")
			(effects
				(font
					(size 1.27 1.27)
				)
				(justify mirror)
			)
		)
		(duplicate_pad_numbers_are_jumpers no)
		(fp_line
			(start 0.7874 -0.4064)
			(end -0.7874 -0.4064)
			(stroke
				(width 0.1524)
				(type default)
			)
			(layer "B.SilkS")
		)
		(fp_line
			(start -0.7874 -0.4064)
			(end -0.7874 0.4064)
			(stroke
				(width 0.1524)
				(type default)
			)
			(layer "B.SilkS")
		)
		(fp_line
			(start 0.7874 0.4064)
			(end 0.7874 -0.4064)
			(stroke
				(width 0.1524)
				(type default)
			)
			(layer "B.SilkS")
		)
		(fp_line
			(start -0.7874 0.4064)
			(end 0.7874 0.4064)
			(stroke
				(width 0.1524)
				(type default)
			)
			(layer "B.SilkS")
		)
		(fp_line
			(start 0.67945 -0.305054)
			(end 0.12065 -0.305054)
			(stroke
				(width 0.1)
				(type default)
			)
			(layer "B.Fab")
		)
		(fp_line
			(start 0.12065 -0.305054)
			(end 0.12065 -0.2794)
			(stroke
				(width 0.1)
				(type default)
			)
			(layer "B.Fab")
		)
		(fp_line
			(start -0.12065 -0.3048)
			(end -0.67945 -0.3048)
			(stroke
				(width 0.1)
				(type default)
			)
			(layer "B.Fab")
		)
		(fp_line
			(start -0.67945 -0.3048)
			(end -0.67945 0.3048)
			(stroke
				(width 0.1)
				(type default)
			)
			(layer "B.Fab")
		)
		(fp_line
			(start 0.12065 -0.2794)
			(end -0.12065 -0.2794)
			(stroke
				(width 0.1)
				(type default)
			)
			(layer "B.Fab")
		)
		(fp_line
			(start -0.12065 -0.2794)
			(end -0.12065 -0.3048)
			(stroke
				(width 0.1)
				(type default)
			)
			(layer "B.Fab")
		)
		(fp_line
			(start 0.12065 0.2794)
			(end 0.12065 0.3048)
			(stroke
				(width 0.1)
				(type default)
			)
			(layer "B.Fab")
		)
		(fp_line
			(start -0.120396 0.2794)
			(end 0.12065 0.2794)
			(stroke
				(width 0.1)
				(type default)
			)
			(layer "B.Fab")
		)
		(fp_line
			(start 0.67945 0.3048)
			(end 0.67945 -0.305054)
			(stroke
				(width 0.1)
				(type default)
			)
			(layer "B.Fab")
		)
		(fp_line
			(start 0.12065 0.3048)
			(end 0.67945 0.3048)
			(stroke
				(width 0.1)
				(type default)
			)
			(layer "B.Fab")
		)
		(fp_line
			(start -0.120396 0.3048)
			(end -0.120396 0.2794)
			(stroke
				(width 0.1)
				(type default)
			)
			(layer "B.Fab")
		)
		(fp_line
			(start -0.67945 0.3048)
			(end -0.120396 0.3048)
			(stroke
				(width 0.1)
				(type default)
			)
			(layer "B.Fab")
		)
		(pad "1" smd circle
			(at 0.40005 0 270)
			(size 0 0)
			(layers "B.Cu" "B.Mask" "B.Paste")
			(net "SPI_BMC_BOOT_CS1_R_N")
		)
		(pad "2" smd circle
			(at -0.40005 0 270)
			(size 0 0)
			(layers "B.Cu" "B.Mask" "B.Paste")
			(net "SPI_BMC_BOOT_CS1_R1_N")
		)
	)
)
